(kicad_pcb
	(version 20260206)
	(generator "pcbnew")
	(generator_version "10.0")
	(general
		(thickness 1.6)
		(legacy_teardrops no)
	)
	(paper "A4")
	(title_block
		(title "Bryce Canyon_F.DPB_16315-1-OCP.brd")
		(comment 1 "Bryce Canyon / footprints 2069-2076 of 2223")
	)
	(layers
		(0 "F.Cu" signal "TOP")
		(4 "In1.Cu" signal "L2GND")
		(6 "In2.Cu" signal "L3")
		(8 "In3.Cu" signal "L4GND")
		(10 "In4.Cu" signal "L5")
		(12 "In5.Cu" signal "L6VCC")
		(14 "In6.Cu" signal "L7VCC")
		(16 "In7.Cu" signal "L8")
		(18 "In8.Cu" signal "L9GND")
		(20 "In9.Cu" signal "L10")
		(22 "In10.Cu" signal "L11GND")
		(2 "B.Cu" signal "BOTTOM")
		(9 "F.Adhes" user "F.Adhesive")
		(11 "B.Adhes" user "B.Adhesive")
		(13 "F.Paste" user "Package Geometry/Pastemask Top")
		(15 "B.Paste" user "Package Geometry/Pastemask Bottom")
		(5 "F.SilkS" user "Ref Des/Silkscreen Top")
		(7 "B.SilkS" user "Ref Des/Silkscreen Bottom")
		(1 "F.Mask" user "Board Geometry/Soldermask Top")
		(3 "B.Mask" user "Board Geometry/Soldermask Bottom")
		(17 "Dwgs.User" user "User.Drawings")
		(19 "Cmts.User" user "User.Comments")
		(21 "Eco1.User" user "User.Eco1")
		(23 "Eco2.User" user "User.Eco2")
		(25 "Edge.Cuts" user "Board Geometry/Outline")
		(27 "Margin" user)
		(31 "F.CrtYd" user "Package Geometry/Place Bound Top")
		(29 "B.CrtYd" user "Package Geometry/Place Bound Bottom")
		(35 "F.Fab" user "Ref Des/Assembly Top")
		(33 "B.Fab" user "Ref Des/Assembly Bottom")
	)
	(footprint ""
		(layer "B.Cu")
		(at 447.431414 -256.391664 180)
		(property "Reference" "R1259"
			(at 0 0 0)
			(layer "B.SilkS")
			(hide yes)
			(effects
				(font
					(size 1.27 1.27)
				)
				(justify mirror)
			)
		)
		(property "Value" "10KR2F-2-GP"
			(at -0.064008 -3.993896 180)
			(unlocked yes)
			(layer "B.Fab")
			(hide yes)
			(effects
				(font
					(size 1.016 1.016)
					(thickness 0.1524)
				)
				(justify mirror)
			)
		)
		(property "Device Type" "R402H16"
			(at -0.064008 -5.517896 180)
			(unlocked yes)
			(layer "B.Fab")
			(hide yes)
			(effects
				(font
					(size 1.016 1.016)
					(thickness 0.1524)
				)
				(justify mirror)
			)
		)
		(duplicate_pad_numbers_are_jumpers no)
		(fp_line
			(start 0.508 -0.9398)
			(end 0.508 0.9398)
			(stroke
				(width 0.1524)
				(type default)
			)
			(layer "B.SilkS")
		)
		(fp_line
			(start -0.508 -0.9398)
			(end 0.508 -0.9398)
			(stroke
				(width 0.1524)
				(type default)
			)
			(layer "B.SilkS")
		)
		(fp_rect
			(start 0.508 0.9398)
			(end -0.508 -0.9398)
			(stroke
				(width 0)
				(type default)
			)
			(fill no)
			(layer "B.CrtYd")
		)
		(fp_rect
			(start 0.508 0.9398)
			(end -0.508 -0.9398)
			(stroke
				(width 0)
				(type default)
			)
			(fill no)
			(layer "B.Fab")
		)
		(pad "1" smd custom
			(at 0 -0.4445)
			(size 0.1397 0.1397)
			(layers "B.Cu" "B.Mask" "B.Paste")
			(net "P5V_C_VFB")
			(options
				(clearance outline)
				(anchor circle)
			)
			(primitives
				(gr_poly
					(pts
						(arc
							(start -0.1778 0.2794)
							(mid -0.249642 0.249642)
							(end -0.2794 0.1778)
						)
						(arc
							(start -0.2794 -0.1778)
							(mid -0.249642 -0.249642)
							(end -0.1778 -0.2794)
						)
						(arc
							(start 0.1778 -0.2794)
							(mid 0.249642 -0.249642)
							(end 0.2794 -0.1778)
						)
						(arc
							(start 0.2794 0.1778)
							(mid 0.249642 0.249642)
							(end 0.1778 0.2794)
						)
					)
					(width 0)
					(fill yes)
				)
			)
		)
		(pad "2" smd custom
			(at 0 0.4445)
			(size 0.1397 0.1397)
			(layers "B.Cu" "B.Mask" "B.Paste")
			(net "AGND_P5V_C")
			(options
				(clearance outline)
				(anchor circle)
			)
			(primitives
				(gr_poly
					(pts
						(arc
							(start -0.1778 0.2794)
							(mid -0.249642 0.249642)
							(end -0.2794 0.1778)
						)
						(arc
							(start -0.2794 -0.1778)
							(mid -0.249642 -0.249642)
							(end -0.1778 -0.2794)
						)
						(arc
							(start 0.1778 -0.2794)
							(mid 0.249642 -0.249642)
							(end 0.2794 -0.1778)
						)
						(arc
							(start 0.2794 0.1778)
							(mid 0.249642 0.249642)
							(end 0.1778 0.2794)
						)
					)
					(width 0)
					(fill yes)
				)
			)
		)
	)
	(footprint ""
		(layer "B.Cu")
		(at 438.713372 -252.076966 180)
		(property "Reference" "C633"
			(at 0 0 0)
			(layer "B.SilkS")
			(hide yes)
			(effects
				(font
					(size 1.27 1.27)
				)
				(justify mirror)
			)
		)
		(property "Value" "SC10U16V5KX-7-GP-U"
			(at 0.0762 -6.1214 180)
			(unlocked yes)
			(layer "B.Fab")
			(hide yes)
			(effects
				(font
					(size 1.016 1.016)
					(thickness 0.1524)
				)
				(justify mirror)
			)
		)
		(property "Device Type" "C805H58"
			(at 0.0762 -8.1534 180)
			(unlocked yes)
			(layer "B.Fab")
			(hide yes)
			(effects
				(font
					(size 1.016 1.016)
					(thickness 0.1524)
				)
				(justify mirror)
			)
		)
		(duplicate_pad_numbers_are_jumpers no)
		(fp_line
			(start -0.635 0)
			(end 0.635 0)
			(stroke
				(width 0.508)
				(type default)
			)
			(layer "B.SilkS")
		)
		(fp_rect
			(start 0.9652 1.778)
			(end -0.9652 -1.778)
			(stroke
				(width 0)
				(type default)
			)
			(fill no)
			(layer "B.CrtYd")
		)
		(fp_poly
			(pts
				(xy 0.9652 -1.778) (xy -0.9652 -1.778) (xy -0.9652 1.778) (xy 0.9652 1.778)
			)
			(stroke
				(width 0)
				(type default)
			)
			(fill no)
			(layer "B.Fab")
		)
		(pad "1" smd rect
			(at 0 -0.9652)
			(size 1.397 1.143)
			(layers "B.Cu" "B.Mask" "B.Paste")
			(net "P12V_A_VIN_U22")
		)
		(pad "2" smd rect
			(at 0 0.9652)
			(size 1.397 1.143)
			(layers "B.Cu" "B.Mask" "B.Paste")
			(net "GND")
		)
	)
	(footprint ""
		(layer "B.Cu")
		(at 407.100024 -164.200078 180)
		(property "Reference" "NUT6"
			(at 0 0 0)
			(layer "B.SilkS")
			(hide yes)
			(effects
				(font
					(size 1.27 1.27)
				)
				(justify mirror)
			)
		)
		(property "Value" "STF256R168H278-GP"
			(at 4.826 0.0508 180)
			(unlocked yes)
			(layer "B.Fab")
			(hide yes)
			(effects
				(font
					(size 1.016 1.016)
					(thickness 0.1524)
				)
				(justify mirror)
			)
		)
		(property "Device Type" "STF256R168H278"
			(at 4.826 -1.4732 180)
			(unlocked yes)
			(layer "B.Fab")
			(hide yes)
			(effects
				(font
					(size 1.016 1.016)
					(thickness 0.1524)
				)
				(justify mirror)
			)
		)
		(duplicate_pad_numbers_are_jumpers no)
		(fp_circle
			(center 0 0)
			(end -3.6068 0)
			(stroke
				(width 0.3048)
				(type default)
			)
			(fill no)
			(layer "B.SilkS")
		)
		(fp_poly
			(pts
				(arc
					(start -2.5019 0)
					(mid 2.5019 0)
					(end -2.5019 0)
				)
			)
			(stroke
				(width 0)
				(type default)
			)
			(fill no)
			(layer "B.CrtYd")
		)
		(fp_poly
			(pts
				(arc
					(start -3.7592 0.00635)
					(mid 3.759205 0)
					(end -3.7592 -0.00635)
				)
				(arc
					(start -2.5019 -0.00635)
					(mid 2.501908 0)
					(end -2.5019 0.00635)
				)
			)
			(stroke
				(width 0)
				(type default)
			)
			(fill no)
			(layer "B.CrtYd")
		)
		(fp_poly
			(pts
				(arc
					(start -3.7592 0)
					(mid 3.7592 0)
					(end -3.7592 0)
				)
			)
			(stroke
				(width 0)
				(type default)
			)
			(fill no)
			(layer "F.CrtYd")
		)
		(fp_poly
			(pts
				(arc
					(start -3.7592 0)
					(mid 3.7592 0)
					(end -3.7592 0)
				)
			)
			(stroke
				(width 0)
				(type default)
			)
			(fill no)
			(layer "B.Fab")
		)
		(fp_poly
			(pts
				(arc
					(start -3.7592 0)
					(mid 3.7592 0)
					(end -3.7592 0)
				)
			)
			(stroke
				(width 0)
				(type default)
			)
			(fill no)
			(layer "F.Fab")
		)
		(pad "1" thru_hole circle
			(at 0 0)
			(size 6.5024 6.5024)
			(drill 4.2672)
			(layers "*.Cu" "*.Mask")
			(remove_unused_layers no)
			(net "Net_10")
			(clearance -0.6096)
			(padstack
				(mode front_inner_back)
				(layer "Inner"
					(shape circle)
					(size 4.6736 4.6736)
					(clearance 0.3048)
				)
				(layer "B.Cu"
					(shape circle)
					(size 6.5024 6.5024)
					(thermal_gap 0.3048)
					(clearance -0.6096)
				)
			)
		)
	)
	(footprint ""
		(layer "B.Cu")
		(at 246.253 -385.2418 -90)
		(property "Reference" "R1154"
			(at 0 0 90)
			(layer "B.SilkS")
			(hide yes)
			(effects
				(font
					(size 1.27 1.27)
				)
				(justify mirror)
			)
		)
		(property "Value" "10R2F-L-GP"
			(at -0.064008 -3.993896 270)
			(unlocked yes)
			(layer "B.Fab")
			(hide yes)
			(effects
				(font
					(size 1.016 1.016)
					(thickness 0.1524)
				)
				(justify mirror)
			)
		)
		(property "Device Type" "R402H14"
			(at -0.064008 -5.517896 270)
			(unlocked yes)
			(layer "B.Fab")
			(hide yes)
			(effects
				(font
					(size 1.016 1.016)
					(thickness 0.1524)
				)
				(justify mirror)
			)
		)
		(duplicate_pad_numbers_are_jumpers no)
		(fp_line
			(start -0.508 -0.9398)
			(end 0.508 -0.9398)
			(stroke
				(width 0.1524)
				(type default)
			)
			(layer "B.SilkS")
		)
		(fp_line
			(start 0.508 -0.9398)
			(end 0.508 0.9398)
			(stroke
				(width 0.1524)
				(type default)
			)
			(layer "B.SilkS")
		)
		(fp_rect
			(start 0.508 0.9398)
			(end -0.508 -0.9398)
			(stroke
				(width 0)
				(type default)
			)
			(fill no)
			(layer "B.CrtYd")
		)
		(fp_rect
			(start 0.508 0.9398)
			(end -0.508 -0.9398)
			(stroke
				(width 0)
				(type default)
			)
			(fill no)
			(layer "B.Fab")
		)
		(pad "1" smd custom
			(at 0 -0.4445 90)
			(size 0.1397 0.1397)
			(layers "B.Cu" "B.Mask" "B.Paste")
			(net "MB3_CM_SENSE_R1_P")
			(options
				(clearance outline)
				(anchor circle)
			)
			(primitives
				(gr_poly
					(pts
						(arc
							(start -0.1778 0.2794)
							(mid -0.249642 0.249642)
							(end -0.2794 0.1778)
						)
						(arc
							(start -0.2794 -0.1778)
							(mid -0.249642 -0.249642)
							(end -0.1778 -0.2794)
						)
						(arc
							(start 0.1778 -0.2794)
							(mid 0.249642 -0.249642)
							(end 0.2794 -0.1778)
						)
						(arc
							(start 0.2794 0.1778)
							(mid 0.249642 0.249642)
							(end 0.1778 0.2794)
						)
					)
					(width 0)
					(fill yes)
				)
			)
		)
		(pad "2" smd custom
			(at 0 0.4445 90)
			(size 0.1397 0.1397)
			(layers "B.Cu" "B.Mask" "B.Paste")
			(net "MB3_CM_SENSE_P")
			(options
				(clearance outline)
				(anchor circle)
			)
			(primitives
				(gr_poly
					(pts
						(arc
							(start -0.1778 0.2794)
							(mid -0.249642 0.249642)
							(end -0.2794 0.1778)
						)
						(arc
							(start -0.2794 -0.1778)
							(mid -0.249642 -0.249642)
							(end -0.1778 -0.2794)
						)
						(arc
							(start 0.1778 -0.2794)
							(mid 0.249642 -0.249642)
							(end 0.2794 -0.1778)
						)
						(arc
							(start 0.2794 0.1778)
							(mid 0.249642 0.249642)
							(end 0.1778 0.2794)
						)
					)
					(width 0)
					(fill yes)
				)
			)
		)
	)
	(footprint ""
		(layer "B.Cu")
		(at 484.251 -225.679 180)
		(property "Reference" "R1279"
			(at 0 0 0)
			(layer "B.SilkS")
			(hide yes)
			(effects
				(font
					(size 1.27 1.27)
				)
				(justify mirror)
			)
		)
		(property "Value" "0R2J-2-GP"
			(at -0.064008 -3.993896 180)
			(unlocked yes)
			(layer "B.Fab")
			(hide yes)
			(effects
				(font
					(size 1.016 1.016)
					(thickness 0.1524)
				)
				(justify mirror)
			)
		)
		(property "Device Type" "R402H16"
			(at -0.064008 -5.517896 180)
			(unlocked yes)
			(layer "B.Fab")
			(hide yes)
			(effects
				(font
					(size 1.016 1.016)
					(thickness 0.1524)
				)
				(justify mirror)
			)
		)
		(duplicate_pad_numbers_are_jumpers no)
		(fp_line
			(start 0.508 -0.9398)
			(end 0.508 0.9398)
			(stroke
				(width 0.1524)
				(type default)
			)
			(layer "B.SilkS")
		)
		(fp_line
			(start -0.508 -0.9398)
			(end 0.508 -0.9398)
			(stroke
				(width 0.1524)
				(type default)
			)
			(layer "B.SilkS")
		)
		(fp_rect
			(start 0.508 0.9398)
			(end -0.508 -0.9398)
			(stroke
				(width 0)
				(type default)
			)
			(fill no)
			(layer "B.CrtYd")
		)
		(fp_rect
			(start 0.508 0.9398)
			(end -0.508 -0.9398)
			(stroke
				(width 0)
				(type default)
			)
			(fill no)
			(layer "B.Fab")
		)
		(pad "1" smd custom
			(at 0 -0.4445)
			(size 0.1397 0.1397)
			(layers "B.Cu" "B.Mask" "B.Paste")
			(net "P5V_D_ROVP")
			(options
				(clearance outline)
				(anchor circle)
			)
			(primitives
				(gr_poly
					(pts
						(arc
							(start -0.1778 0.2794)
							(mid -0.249642 0.249642)
							(end -0.2794 0.1778)
						)
						(arc
							(start -0.2794 -0.1778)
							(mid -0.249642 -0.249642)
							(end -0.1778 -0.2794)
						)
						(arc
							(start 0.1778 -0.2794)
							(mid 0.249642 -0.249642)
							(end 0.2794 -0.1778)
						)
						(arc
							(start 0.2794 0.1778)
							(mid 0.249642 0.249642)
							(end 0.1778 0.2794)
						)
					)
					(width 0)
					(fill yes)
				)
			)
		)
		(pad "2" smd custom
			(at 0 0.4445)
			(size 0.1397 0.1397)
			(layers "B.Cu" "B.Mask" "B.Paste")
			(net "AGND_P5V_D")
			(options
				(clearance outline)
				(anchor circle)
			)
			(primitives
				(gr_poly
					(pts
						(arc
							(start -0.1778 0.2794)
							(mid -0.249642 0.249642)
							(end -0.2794 0.1778)
						)
						(arc
							(start -0.2794 -0.1778)
							(mid -0.249642 -0.249642)
							(end -0.1778 -0.2794)
						)
						(arc
							(start 0.1778 -0.2794)
							(mid 0.249642 -0.249642)
							(end 0.2794 -0.1778)
						)
						(arc
							(start 0.2794 0.1778)
							(mid 0.249642 0.249642)
							(end 0.1778 0.2794)
						)
					)
					(width 0)
					(fill yes)
				)
			)
		)
	)
	(footprint ""
		(layer "B.Cu")
		(at 222.2246 -120.2182)
		(property "Reference" "R188"
			(at 0 0 0)
			(layer "B.SilkS")
			(hide yes)
			(effects
				(font
					(size 1.27 1.27)
				)
				(justify mirror)
			)
		)
		(property "Value" "4K7R2F-GP"
			(at -0.064008 -3.993896 0)
			(unlocked yes)
			(layer "B.Fab")
			(hide yes)
			(effects
				(font
					(size 1.016 1.016)
					(thickness 0.1524)
				)
				(justify mirror)
			)
		)
		(property "Device Type" "R402H16"
			(at -0.064008 -5.517896 0)
			(unlocked yes)
			(layer "B.Fab")
			(hide yes)
			(effects
				(font
					(size 1.016 1.016)
					(thickness 0.1524)
				)
				(justify mirror)
			)
		)
		(duplicate_pad_numbers_are_jumpers no)
		(fp_line
			(start -0.508 -0.9398)
			(end 0.508 -0.9398)
			(stroke
				(width 0.1524)
				(type default)
			)
			(layer "B.SilkS")
		)
		(fp_line
			(start 0.508 -0.9398)
			(end 0.508 0.9398)
			(stroke
				(width 0.1524)
				(type default)
			)
			(layer "B.SilkS")
		)
		(fp_rect
			(start 0.508 0.9398)
			(end -0.508 -0.9398)
			(stroke
				(width 0)
				(type default)
			)
			(fill no)
			(layer "B.CrtYd")
		)
		(fp_rect
			(start 0.508 0.9398)
			(end -0.508 -0.9398)
			(stroke
				(width 0)
				(type default)
			)
			(fill no)
			(layer "B.Fab")
		)
		(pad "1" smd custom
			(at 0 -0.4445 180)
			(size 0.1397 0.1397)
			(layers "B.Cu" "B.Mask" "B.Paste")
			(net "TXS0102_A_OE")
			(options
				(clearance outline)
				(anchor circle)
			)
			(primitives
				(gr_poly
					(pts
						(arc
							(start -0.1778 0.2794)
							(mid -0.249642 0.249642)
							(end -0.2794 0.1778)
						)
						(arc
							(start -0.2794 -0.1778)
							(mid -0.249642 -0.249642)
							(end -0.1778 -0.2794)
						)
						(arc
							(start 0.1778 -0.2794)
							(mid 0.249642 -0.249642)
							(end 0.2794 -0.1778)
						)
						(arc
							(start 0.2794 0.1778)
							(mid 0.249642 0.249642)
							(end 0.1778 0.2794)
						)
					)
					(width 0)
					(fill yes)
				)
			)
		)
		(pad "2" smd custom
			(at 0 0.4445 180)
			(size 0.1397 0.1397)
			(layers "B.Cu" "B.Mask" "B.Paste")
			(net "P3V3_STBY_A")
			(options
				(clearance outline)
				(anchor circle)
			)
			(primitives
				(gr_poly
					(pts
						(arc
							(start -0.1778 0.2794)
							(mid -0.249642 0.249642)
							(end -0.2794 0.1778)
						)
						(arc
							(start -0.2794 -0.1778)
							(mid -0.249642 -0.249642)
							(end -0.1778 -0.2794)
						)
						(arc
							(start 0.1778 -0.2794)
							(mid 0.249642 -0.249642)
							(end 0.2794 -0.1778)
						)
						(arc
							(start 0.2794 0.1778)
							(mid 0.249642 0.249642)
							(end 0.1778 0.2794)
						)
					)
					(width 0)
					(fill yes)
				)
			)
		)
	)
	(footprint ""
		(layer "B.Cu")
		(at 479.552 -228.092)
		(property "Reference" "C654"
			(at 0 0 0)
			(layer "B.SilkS")
			(hide yes)
			(effects
				(font
					(size 1.27 1.27)
				)
				(justify mirror)
			)
		)
		(property "Value" "SC1U16V3KX-5GP"
			(at 0 -2.8194 0)
			(unlocked yes)
			(layer "B.Fab")
			(hide yes)
			(effects
				(font
					(size 1.016 1.016)
					(thickness 0.1524)
				)
				(justify mirror)
			)
		)
		(property "Device Type" "C603H36"
			(at 0 -4.3434 0)
			(unlocked yes)
			(layer "B.Fab")
			(hide yes)
			(effects
				(font
					(size 1.016 1.016)
					(thickness 0.1524)
				)
				(justify mirror)
			)
		)
		(duplicate_pad_numbers_are_jumpers no)
		(fp_line
			(start -0.508 0)
			(end 0.508 0)
			(stroke
				(width 0.2032)
				(type default)
			)
			(layer "B.SilkS")
		)
		(fp_rect
			(start 0.5842 1.3335)
			(end -0.5842 -1.3335)
			(stroke
				(width 0)
				(type default)
			)
			(fill no)
			(layer "B.CrtYd")
		)
		(fp_rect
			(start 0.5842 1.3335)
			(end -0.5842 -1.3335)
			(stroke
				(width 0)
				(type default)
			)
			(fill no)
			(layer "B.Fab")
		)
		(pad "1" smd custom
			(at 0 -0.762 180)
			(size 0.2159 0.2159)
			(layers "B.Cu" "B.Mask" "B.Paste")
			(net "P5V_D_EN_R")
			(options
				(clearance outline)
				(anchor circle)
			)
			(primitives
				(gr_poly
					(pts
						(arc
							(start -0.3302 0.4318)
							(mid -0.402042 0.402042)
							(end -0.4318 0.3302)
						)
						(arc
							(start -0.4318 -0.3302)
							(mid -0.402042 -0.402042)
							(end -0.3302 -0.4318)
						)
						(arc
							(start 0.3302 -0.4318)
							(mid 0.402042 -0.402042)
							(end 0.4318 -0.3302)
						)
						(arc
							(start 0.4318 0.3302)
							(mid 0.402042 0.402042)
							(end 0.3302 0.4318)
						)
					)
					(width 0)
					(fill yes)
				)
			)
		)
		(pad "2" smd custom
			(at 0 0.762 180)
			(size 0.2159 0.2159)
			(layers "B.Cu" "B.Mask" "B.Paste")
			(net "GND")
			(options
				(clearance outline)
				(anchor circle)
			)
			(primitives
				(gr_poly
					(pts
						(arc
							(start -0.3302 0.4318)
							(mid -0.402042 0.402042)
							(end -0.4318 0.3302)
						)
						(arc
							(start -0.4318 -0.3302)
							(mid -0.402042 -0.402042)
							(end -0.3302 -0.4318)
						)
						(arc
							(start 0.3302 -0.4318)
							(mid 0.402042 -0.402042)
							(end 0.4318 -0.3302)
						)
						(arc
							(start 0.4318 0.3302)
							(mid 0.402042 0.402042)
							(end 0.3302 0.4318)
						)
					)
					(width 0)
					(fill yes)
				)
			)
		)
	)
	(footprint ""
		(layer "B.Cu")
		(at 185.089292 -239.238028 180)
		(property "Reference" "C686"
			(at 0 0 0)
			(layer "B.SilkS")
			(hide yes)
			(effects
				(font
					(size 1.27 1.27)
				)
				(justify mirror)
			)
		)
		(property "Value" "SC10U6D3V5KX-4GP"
			(at 0.0762 -6.1214 180)
			(unlocked yes)
			(layer "B.Fab")
			(hide yes)
			(effects
				(font
					(size 1.016 1.016)
					(thickness 0.1524)
				)
				(justify mirror)
			)
		)
		(property "Device Type" "C805H58"
			(at 0.0762 -8.1534 180)
			(unlocked yes)
			(layer "B.Fab")
			(hide yes)
			(effects
				(font
					(size 1.016 1.016)
					(thickness 0.1524)
				)
				(justify mirror)
			)
		)
		(duplicate_pad_numbers_are_jumpers no)
		(fp_line
			(start -0.635 0)
			(end 0.635 0)
			(stroke
				(width 0.508)
				(type default)
			)
			(layer "B.SilkS")
		)
		(fp_rect
			(start 0.9652 1.778)
			(end -0.9652 -1.778)
			(stroke
				(width 0)
				(type default)
			)
			(fill no)
			(layer "B.CrtYd")
		)
		(fp_poly
			(pts
				(xy 0.9652 -1.778) (xy -0.9652 -1.778) (xy -0.9652 1.778) (xy 0.9652 1.778)
			)
			(stroke
				(width 0)
				(type default)
			)
			(fill no)
			(layer "B.Fab")
		)
		(pad "1" smd rect
			(at 0 -0.9652)
			(size 1.397 1.143)
			(layers "B.Cu" "B.Mask" "B.Paste")
			(net "P3V3_STBY_A")
		)
		(pad "2" smd rect
			(at 0 0.9652)
			(size 1.397 1.143)
			(layers "B.Cu" "B.Mask" "B.Paste")
			(net "GND")
		)
	)
)
